# S9S_MB_2U (Grand Teton) — schematic netlist excerpt (pin names and nets, part order shuffled) for the footprints in the layout excerpt that follows; sources: Cadence DE-HDL packaged netlist, KiCad conversion of 03242023_DA0F0TMBIJ0_F0T_Motherboard_J_brd_V01_OCP.brd

C1773  Q_CAP  1000PF 50V 5% EMPTY  pkg 0402  page 148 : A = BIC_MONITER_ISO ; B = GND
PC270  Q_CAP  2.2UF 10V 10% X6S  pkg C0402  page 268 : A = PVCCIN_CPU0_VDD4 ; B = GND

(kicad_pcb
	(version 20260206)
	(generator "pcbnew")
	(generator_version "10.0")
	(general
		(thickness 1.6)
		(legacy_teardrops no)
	)
	(paper "A4")
	(title_block
		(title "03242023_DA0F0TMBIJ0_F0T_Motherboard_J_brd_V01_OCP.brd")
		(comment 1 "Grand Teton / footprints 3214-3215 of 6105")
	)
	(layers
		(0 "F.Cu" signal "TOP")
		(4 "In1.Cu" signal "GND")
		(6 "In2.Cu" signal "IN1")
		(8 "In3.Cu" signal "GND1")
		(10 "In4.Cu" signal "IN2")
		(12 "In5.Cu" signal "GND2")
		(14 "In6.Cu" signal "IN3")
		(16 "In7.Cu" signal "GND3")
		(18 "In8.Cu" signal "VCC")
		(20 "In9.Cu" signal "VCC1")
		(22 "In10.Cu" signal "GND4")
		(24 "In11.Cu" signal "IN4")
		(26 "In12.Cu" signal "GND5")
		(28 "In13.Cu" signal "IN5")
		(30 "In14.Cu" signal "GND6")
		(32 "In15.Cu" signal "IN6")
		(34 "In16.Cu" signal "GND7")
		(2 "B.Cu" signal "BOTTOM")
		(9 "F.Adhes" user "F.Adhesive")
		(11 "B.Adhes" user "B.Adhesive")
		(13 "F.Paste" user "Package Geometry/Pastemask Top")
		(15 "B.Paste" user "Package Geometry/Pastemask Bottom")
		(5 "F.SilkS" user "Ref Des/Silkscreen Top")
		(7 "B.SilkS" user "Ref Des/Silkscreen Bottom")
		(1 "F.Mask" user "Board Geometry/Soldermask Top")
		(3 "B.Mask" user "Board Geometry/Soldermask Bottom")
		(17 "Dwgs.User" user "User.Drawings")
		(19 "Cmts.User" user "User.Comments")
		(21 "Eco1.User" user "User.Eco1")
		(23 "Eco2.User" user "User.Eco2")
		(25 "Edge.Cuts" user "Board Geometry/Outline")
		(27 "Margin" user)
		(31 "F.CrtYd" user "Package Geometry/Place Bound Top")
		(29 "B.CrtYd" user "Package Geometry/Place Bound Bottom")
		(35 "F.Fab" user "Ref Des/Assembly Top")
		(33 "B.Fab" user "Ref Des/Assembly Bottom")
	)
	(footprint ""
		(layer "F.Cu")
		(at 118.849902 -410.129228)
		(property "Reference" "C1773"
			(at 0 0 0)
			(layer "F.SilkS")
			(hide yes)
			(effects
				(font
					(size 1.27 1.27)
				)
			)
		)
		(property "Value" ""
			(at 0 0 0)
			(layer "F.Fab")
			(effects
				(font
					(size 1.27 1.27)
				)
			)
		)
		(duplicate_pad_numbers_are_jumpers no)
		(fp_line
			(start -0.7874 -0.4064)
			(end 0.7874 -0.4064)
			(stroke
				(width 0.1524)
				(type default)
			)
			(layer "F.SilkS")
		)
		(fp_line
			(start -0.7874 0.4064)
			(end -0.7874 -0.4064)
			(stroke
				(width 0.1524)
				(type default)
			)
			(layer "F.SilkS")
		)
		(fp_line
			(start 0.7874 -0.4064)
			(end 0.7874 0.4064)
			(stroke
				(width 0.1524)
				(type default)
			)
			(layer "F.SilkS")
		)
		(fp_line
			(start 0.7874 0.4064)
			(end -0.7874 0.4064)
			(stroke
				(width 0.1524)
				(type default)
			)
			(layer "F.SilkS")
		)
		(fp_line
			(start -0.67945 -0.305054)
			(end -0.12065 -0.305054)
			(stroke
				(width 0.1)
				(type default)
			)
			(layer "F.Fab")
		)
		(fp_line
			(start -0.67945 0.3048)
			(end -0.67945 -0.305054)
			(stroke
				(width 0.1)
				(type default)
			)
			(layer "F.Fab")
		)
		(fp_line
			(start -0.12065 -0.305054)
			(end -0.12065 -0.2794)
			(stroke
				(width 0.1)
				(type default)
			)
			(layer "F.Fab")
		)
		(fp_line
			(start -0.12065 -0.2794)
			(end 0.12065 -0.2794)
			(stroke
				(width 0.1)
				(type default)
			)
			(layer "F.Fab")
		)
		(fp_line
			(start -0.12065 0.2794)
			(end -0.12065 0.3048)
			(stroke
				(width 0.1)
				(type default)
			)
			(layer "F.Fab")
		)
		(fp_line
			(start -0.12065 0.3048)
			(end -0.67945 0.3048)
			(stroke
				(width 0.1)
				(type default)
			)
			(layer "F.Fab")
		)
		(fp_line
			(start 0.120396 0.2794)
			(end -0.12065 0.2794)
			(stroke
				(width 0.1)
				(type default)
			)
			(layer "F.Fab")
		)
		(fp_line
			(start 0.120396 0.3048)
			(end 0.120396 0.2794)
			(stroke
				(width 0.1)
				(type default)
			)
			(layer "F.Fab")
		)
		(fp_line
			(start 0.12065 -0.3048)
			(end 0.67945 -0.3048)
			(stroke
				(width 0.1)
				(type default)
			)
			(layer "F.Fab")
		)
		(fp_line
			(start 0.12065 -0.2794)
			(end 0.12065 -0.3048)
			(stroke
				(width 0.1)
				(type default)
			)
			(layer "F.Fab")
		)
		(fp_line
			(start 0.67945 -0.3048)
			(end 0.67945 0.3048)
			(stroke
				(width 0.1)
				(type default)
			)
			(layer "F.Fab")
		)
		(fp_line
			(start 0.67945 0.3048)
			(end 0.120396 0.3048)
			(stroke
				(width 0.1)
				(type default)
			)
			(layer "F.Fab")
		)
		(pad "1" smd circle
			(at -0.40005 0)
			(size 0 0)
			(layers "F.Cu" "F.Mask" "F.Paste")
			(net "BIC_MONITER_ISO")
		)
		(pad "2" smd circle
			(at 0.40005 0)
			(size 0 0)
			(layers "F.Cu" "F.Mask" "F.Paste")
			(net "GND")
		)
	)
	(footprint ""
		(layer "F.Cu")
		(at 365.844328 -336.192368 90)
		(property "Reference" "PC270"
			(at 0 0 90)
			(layer "F.SilkS")
			(hide yes)
			(effects
				(font
					(size 1.27 1.27)
				)
			)
		)
		(property "Value" ""
			(at 0 0 90)
			(layer "F.Fab")
			(effects
				(font
					(size 1.27 1.27)
				)
			)
		)
		(duplicate_pad_numbers_are_jumpers no)
		(fp_line
			(start 0.7874 -0.4064)
			(end 0.7874 0.4064)
			(stroke
				(width 0.1524)
				(type default)
			)
			(layer "F.SilkS")
		)
		(fp_line
			(start -0.7874 -0.4064)
			(end 0.7874 -0.4064)
			(stroke
				(width 0.1524)
				(type default)
			)
			(layer "F.SilkS")
		)
		(fp_line
			(start 0.7874 0.4064)
			(end -0.7874 0.4064)
			(stroke
				(width 0.1524)
				(type default)
			)
			(layer "F.SilkS")
		)
		(fp_line
			(start -0.7874 0.4064)
			(end -0.7874 -0.4064)
			(stroke
				(width 0.1524)
				(type default)
			)
			(layer "F.SilkS")
		)
		(fp_line
			(start -0.12065 -0.305054)
			(end -0.12065 -0.2794)
			(stroke
				(width 0.1)
				(type default)
			)
			(layer "F.Fab")
		)
		(fp_line
			(start -0.67945 -0.305054)
			(end -0.12065 -0.305054)
			(stroke
				(width 0.1)
				(type default)
			)
			(layer "F.Fab")
		)
		(fp_line
			(start 0.67945 -0.3048)
			(end 0.67945 0.3048)
			(stroke
				(width 0.1)
				(type default)
			)
			(layer "F.Fab")
		)
		(fp_line
			(start 0.12065 -0.3048)
			(end 0.67945 -0.3048)
			(stroke
				(width 0.1)
				(type default)
			)
			(layer "F.Fab")
		)
		(fp_line
			(start 0.12065 -0.2794)
			(end 0.12065 -0.3048)
			(stroke
				(width 0.1)
				(type default)
			)
			(layer "F.Fab")
		)
		(fp_line
			(start -0.12065 -0.2794)
			(end 0.12065 -0.2794)
			(stroke
				(width 0.1)
				(type default)
			)
			(layer "F.Fab")
		)
		(fp_line
			(start 0.120396 0.2794)
			(end -0.12065 0.2794)
			(stroke
				(width 0.1)
				(type default)
			)
			(layer "F.Fab")
		)
		(fp_line
			(start -0.12065 0.2794)
			(end -0.12065 0.3048)
			(stroke
				(width 0.1)
				(type default)
			)
			(layer "F.Fab")
		)
		(fp_line
			(start 0.67945 0.3048)
			(end 0.120396 0.3048)
			(stroke
				(width 0.1)
				(type default)
			)
			(layer "F.Fab")
		)
		(fp_line
			(start 0.120396 0.3048)
			(end 0.120396 0.2794)
			(stroke
				(width 0.1)
				(type default)
			)
			(layer "F.Fab")
		)
		(fp_line
			(start -0.12065 0.3048)
			(end -0.67945 0.3048)
			(stroke
				(width 0.1)
				(type default)
			)
			(layer "F.Fab")
		)
		(fp_line
			(start -0.67945 0.3048)
			(end -0.67945 -0.305054)
			(stroke
				(width 0.1)
				(type default)
			)
			(layer "F.Fab")
		)
		(pad "1" smd circle
			(at -0.40005 0 90)
			(size 0 0)
			(layers "F.Cu" "F.Mask" "F.Paste")
			(net "PVCCIN_CPU0_VDD4")
		)
		(pad "2" smd circle
			(at 0.40005 0 90)
			(size 0 0)
			(layers "F.Cu" "F.Mask" "F.Paste")
			(net "GND")
		)
	)
)
